# S9S_MB_2U (Grand Teton) — schematic netlist excerpt (pin names and nets, part order shuffled) for the footprints in the layout excerpt that follows; sources: Cadence DE-HDL packaged netlist, KiCad conversion of 03242023_DA0F0TMBIJ0_F0T_Motherboard_J_brd_V01_OCP.brd

U90  PI6CV304LE  IC  pkg TSSOP8  page 155
  CLK_IN  = CLK_50M_RMII_R
  OE  = CLK_50M_EN
  Y0  = CLK_50M_BMC_MAC_R
  GND  = GND
  Y1  = CLK_50M_NCSI_OCP_1
  VDD  = P3V3_AUX
  Y2  = CLK_50M_NCSI_OCP_2
  Y3  = TP_CLK_50M_PCH_LOM

(kicad_pcb
	(version 20260206)
	(generator "pcbnew")
	(generator_version "10.0")
	(general
		(thickness 1.6)
		(legacy_teardrops no)
	)
	(paper "A4")
	(title_block
		(title "03242023_DA0F0TMBIJ0_F0T_Motherboard_J_brd_V01_OCP.brd")
		(comment 1 "Grand Teton / footprints 3568-3568 of 6105")
	)
	(layers
		(0 "F.Cu" signal "TOP")
		(4 "In1.Cu" signal "GND")
		(6 "In2.Cu" signal "IN1")
		(8 "In3.Cu" signal "GND1")
		(10 "In4.Cu" signal "IN2")
		(12 "In5.Cu" signal "GND2")
		(14 "In6.Cu" signal "IN3")
		(16 "In7.Cu" signal "GND3")
		(18 "In8.Cu" signal "VCC")
		(20 "In9.Cu" signal "VCC1")
		(22 "In10.Cu" signal "GND4")
		(24 "In11.Cu" signal "IN4")
		(26 "In12.Cu" signal "GND5")
		(28 "In13.Cu" signal "IN5")
		(30 "In14.Cu" signal "GND6")
		(32 "In15.Cu" signal "IN6")
		(34 "In16.Cu" signal "GND7")
		(2 "B.Cu" signal "BOTTOM")
		(9 "F.Adhes" user "F.Adhesive")
		(11 "B.Adhes" user "B.Adhesive")
		(13 "F.Paste" user "Package Geometry/Pastemask Top")
		(15 "B.Paste" user "Package Geometry/Pastemask Bottom")
		(5 "F.SilkS" user "Ref Des/Silkscreen Top")
		(7 "B.SilkS" user "Ref Des/Silkscreen Bottom")
		(1 "F.Mask" user "Board Geometry/Soldermask Top")
		(3 "B.Mask" user "Board Geometry/Soldermask Bottom")
		(17 "Dwgs.User" user "User.Drawings")
		(19 "Cmts.User" user "User.Comments")
		(21 "Eco1.User" user "User.Eco1")
		(23 "Eco2.User" user "User.Eco2")
		(25 "Edge.Cuts" user "Board Geometry/Outline")
		(27 "Margin" user)
		(31 "F.CrtYd" user "Package Geometry/Place Bound Top")
		(29 "B.CrtYd" user "Package Geometry/Place Bound Bottom")
		(35 "F.Fab" user "Ref Des/Assembly Top")
		(33 "B.Fab" user "Ref Des/Assembly Bottom")
	)
	(footprint ""
		(layer "F.Cu")
		(at 214.344504 -17.766792 -90)
		(property "Reference" "U90"
			(at -1.504696 -2.230882 0)
			(unlocked yes)
			(layer "F.SilkS")
			(effects
				(font
					(size 0.7874 0.5842)
					(thickness 0.1524)
				)
				(justify left)
			)
		)
		(property "Value" ""
			(at 0 0 270)
			(layer "F.Fab")
			(effects
				(font
					(size 1.27 1.27)
				)
			)
		)
		(duplicate_pad_numbers_are_jumpers no)
		(fp_line
			(start -2.25044 1.5494)
			(end -2.25044 1.3208)
			(stroke
				(width 0.1524)
				(type default)
			)
			(layer "F.SilkS")
		)
		(fp_line
			(start 2.25044 1.5494)
			(end -2.25044 1.5494)
			(stroke
				(width 0.1524)
				(type default)
			)
			(layer "F.SilkS")
		)
		(fp_line
			(start 2.25044 1.3208)
			(end 2.25044 1.5494)
			(stroke
				(width 0.1524)
				(type default)
			)
			(layer "F.SilkS")
		)
		(fp_line
			(start 0 -0.9652)
			(end -0.5842 -1.5494)
			(stroke
				(width 0.1524)
				(type default)
			)
			(layer "F.SilkS")
		)
		(fp_line
			(start 2.25044 -1.3208)
			(end 2.25044 -1.5494)
			(stroke
				(width 0.1524)
				(type default)
			)
			(layer "F.SilkS")
		)
		(fp_line
			(start -2.25044 -1.5494)
			(end -2.25044 -1.3208)
			(stroke
				(width 0.1524)
				(type default)
			)
			(layer "F.SilkS")
		)
		(fp_line
			(start -0.5842 -1.5494)
			(end -2.25044 -1.5494)
			(stroke
				(width 0.1524)
				(type default)
			)
			(layer "F.SilkS")
		)
		(fp_line
			(start 0.5842 -1.5494)
			(end 0 -0.9652)
			(stroke
				(width 0.1524)
				(type default)
			)
			(layer "F.SilkS")
		)
		(fp_line
			(start 2.0066 -1.5494)
			(end 0.5842 -1.5494)
			(stroke
				(width 0.1524)
				(type default)
			)
			(layer "F.SilkS")
		)
		(fp_line
			(start 2.25044 -1.5494)
			(end 0.5842 -1.5494)
			(stroke
				(width 0.1524)
				(type default)
			)
			(layer "F.SilkS")
		)
		(fp_poly
			(pts
				(xy -4.36372 -1.344168) (xy -3.81 -1.016) (xy -4.36372 -0.719328)
			)
			(stroke
				(width 0)
				(type default)
			)
			(fill yes)
			(layer "F.SilkS")
		)
		(fp_line
			(start -2.25044 1.5494)
			(end 2.25044 1.5494)
			(stroke
				(width 0.1)
				(type default)
			)
			(layer "F.Fab")
		)
		(fp_line
			(start -2.25044 1.5494)
			(end -2.25044 1.12522)
			(stroke
				(width 0.1)
				(type default)
			)
			(layer "F.Fab")
		)
		(fp_line
			(start 2.25044 1.5494)
			(end 2.25044 1.12522)
			(stroke
				(width 0.1)
				(type default)
			)
			(layer "F.Fab")
		)
		(fp_line
			(start 2.25044 1.5494)
			(end 2.25044 -1.5494)
			(stroke
				(width 0.1)
				(type default)
			)
			(layer "F.Fab")
		)
		(fp_line
			(start 2.25044 1.143)
			(end 2.25044 1.0922)
			(stroke
				(width 0.1)
				(type default)
			)
			(layer "F.Fab")
		)
		(fp_line
			(start -3.302 1.12522)
			(end -3.302 -1.12522)
			(stroke
				(width 0.1)
				(type default)
			)
			(layer "F.Fab")
		)
		(fp_line
			(start -2.25044 1.12522)
			(end -3.302 1.12522)
			(stroke
				(width 0.1)
				(type default)
			)
			(layer "F.Fab")
		)
		(fp_line
			(start 2.25044 1.12522)
			(end 3.302 1.12522)
			(stroke
				(width 0.1)
				(type default)
			)
			(layer "F.Fab")
		)
		(fp_line
			(start 3.302 1.12522)
			(end 3.302 -1.12522)
			(stroke
				(width 0.1)
				(type default)
			)
			(layer "F.Fab")
		)
		(fp_line
			(start -3.302 -1.12522)
			(end -2.25044 -1.12522)
			(stroke
				(width 0.1)
				(type default)
			)
			(layer "F.Fab")
		)
		(fp_line
			(start -2.25044 -1.12522)
			(end -2.25044 -1.5494)
			(stroke
				(width 0.1)
				(type default)
			)
			(layer "F.Fab")
		)
		(fp_line
			(start 2.25044 -1.12522)
			(end 2.25044 -1.4986)
			(stroke
				(width 0.1)
				(type default)
			)
			(layer "F.Fab")
		)
		(fp_line
			(start 3.302 -1.12522)
			(end 2.25044 -1.12522)
			(stroke
				(width 0.1)
				(type default)
			)
			(layer "F.Fab")
		)
		(fp_line
			(start -2.25044 -1.5494)
			(end -2.25044 1.5494)
			(stroke
				(width 0.1)
				(type default)
			)
			(layer "F.Fab")
		)
		(fp_line
			(start 2.25044 -1.5494)
			(end -2.25044 -1.5494)
			(stroke
				(width 0.1)
				(type default)
			)
			(layer "F.Fab")
		)
		(fp_poly
			(pts
				(xy -4.36372 -0.719328) (xy -4.36372 -1.344168) (xy -3.81 -1.016)
			)
			(stroke
				(width 0)
				(type default)
			)
			(fill yes)
			(layer "F.Fab")
		)
		(pad "1" smd rect
			(at -2.921 -0.975106 180)
			(size 0.3556 1.4986)
			(layers "F.Cu" "F.Mask" "F.Paste")
			(net "CLK_50M_RMII_R")
		)
		(pad "2" smd rect
			(at -2.921 -0.32512 180)
			(size 0.3556 1.4986)
			(layers "F.Cu" "F.Mask" "F.Paste")
			(net "CLK_50M_EN")
		)
		(pad "3" smd rect
			(at -2.921 0.32512 180)
			(size 0.3556 1.4986)
			(layers "F.Cu" "F.Mask" "F.Paste")
			(net "CLK_50M_BMC_MAC_R")
		)
		(pad "4" smd rect
			(at -2.921 0.975106 180)
			(size 0.3556 1.4986)
			(layers "F.Cu" "F.Mask" "F.Paste")
			(net "GND")
		)
		(pad "5" smd rect
			(at 2.921 0.975106 180)
			(size 0.3556 1.4986)
			(layers "F.Cu" "F.Mask" "F.Paste")
			(net "CLK_50M_NCSI_OCP_1")
		)
		(pad "6" smd rect
			(at 2.921 0.32512 180)
			(size 0.3556 1.4986)
			(layers "F.Cu" "F.Mask" "F.Paste")
			(net "P3V3_AUX")
		)
		(pad "7" smd rect
			(at 2.921 -0.32512 180)
			(size 0.3556 1.4986)
			(layers "F.Cu" "F.Mask" "F.Paste")
			(net "CLK_50M_NCSI_OCP_2")
		)
		(pad "8" smd rect
			(at 2.921 -0.975106 180)
			(size 0.3556 1.4986)
			(layers "F.Cu" "F.Mask" "F.Paste")
			(net "TP_CLK_50M_PCH_LOM")
		)
	)
)
